# T6G (Grand Teton) — schematic netlist excerpt (pin names and nets, part order shuffled) for the footprints in the layout excerpt that follows; sources: Cadence DE-HDL packaged netlist, KiCad conversion of 04192023_DAF0TMB3IC0_F0TG_MB_C_brd_V02_OCP.brd

J68  SCONN288_DDR506112002KQ  IO  pkg DDR288S_1-1VXC  page 95
  VIN_BULK0  = P12V_MEM_CPU0
  RFU0  = NC
  VIN_MGMT  = P3V3_AUX
  HSCL  = I3C_SPD_DDRJ_CPU0_SCL
  HSDA  = I3C_SPD_DDRJ_CPU0_SDA
  VSS0  = GND
  DQ0_A  = M_J_CPU0_SA_DQ<0>
  VSS1  = GND
  DQ1_A  = M_J_CPU0_SA_DQ<1>
  VSS2  = GND
  DQS0_A_T  = M_J_CPU0_SA_DQS_DP<0>
  DQS0_A_C  = M_J_CPU0_SA_DQS_DN<0>
  VSS3  = GND
  DQ4_A  = M_J_CPU0_SA_DQ<4>
  VSS4  = GND
  DQ5_A  = M_J_CPU0_SA_DQ<5>
  VSS5  = GND
  DQ8_A  = M_J_CPU0_SA_DQ<8>
  VSS6  = GND
  DQ9_A  = M_J_CPU0_SA_DQ<9>
  VSS7  = GND
  DQS1_A_T  = M_J_CPU0_SA_DQS_DP<1>
  DQS1_A_C  = M_J_CPU0_SA_DQS_DN<1>
  VSS8  = GND
  DQ12_A  = M_J_CPU0_SA_DQ<12>
  VSS9  = GND
  DQ13_A  = M_J_CPU0_SA_DQ<13>
  VSS10  = GND
  DQ16_A  = M_J_CPU0_SA_DQ<16>
  VSS11  = GND
  DQ17_A  = M_J_CPU0_SA_DQ<17>
  VSS12  = GND
  DQS2_A_T  = M_J_CPU0_SA_DQS_DP<2>
  DQS2_A_C  = M_J_CPU0_SA_DQS_DN<2>
  VSS13  = GND
  DQ20_A  = M_J_CPU0_SA_DQ<20>
  VSS14  = GND
  DQ21_A  = M_J_CPU0_SA_DQ<21>
  VSS15  = GND
  DQ24_A  = M_J_CPU0_SA_DQ<24>
  VSS16  = GND
  DQ25_A  = M_J_CPU0_SA_DQ<25>
  VSS17  = GND
  DQS3_A_T  = M_J_CPU0_SA_DQS_DP<3>
  DQS3_A_C  = M_J_CPU0_SA_DQS_DN<3>
  VSS18  = GND
  DQ28_A  = M_J_CPU0_SA_DQ<28>
  VSS19  = GND
  DQ29_A  = M_J_CPU0_SA_DQ<29>
  VSS20  = GND
  CB0_A  = M_J_CPU0_SA_CB<0>
  VSS21  = GND
  CB1_A  = M_J_CPU0_SA_CB<1>
  VSS22  = GND
  DQS4_A_T  = M_J_CPU0_SA_DQS_DP<4>
  DQS4_A_C  = M_J_CPU0_SA_DQS_DN<4>
  VSS23  = GND
  CB4_A  = M_J_CPU0_SA_CB<4>
  VSS24  = GND
  CB5_A  = M_J_CPU0_SA_CB<5>
  VSS25  = GND
  ALERT_N  = M_J_CPU0_ALERT_N
  VSS26  = GND
  CS0_A_N  = M_J_CPU0_SA_CS_N<0>
  VSS27  = GND
  CA0_A  = M_J_CPU0_SA_CA<0>
  VSS28  = GND
  CA2_A  = M_J_CPU0_SA_CA<2>
  VSS29  = GND
  CA4_A  = M_J_CPU0_SA_CA<4>
  VSS30  = GND
  CA6_A  = M_J_CPU0_SA_CA<6>
  VSS31  = GND
  PAR_A  = M_J_CPU0_SA_PAR
  VSS32  = GND
  CA0_B  = M_J_CPU0_SB_CA<0>
  VSS33  = GND
  CA2_B  = M_J_CPU0_SB_CA<2>
  VSS34  = GND
  CA4_B  = M_J_CPU0_SB_CA<4>
  VSS35  = GND
  CA6_B  = M_J_CPU0_SB_CA<6>
  VSS36  = GND
  CS0_B_N  = M_J_CPU0_SB_CS_N<0>
  VSS37  = GND
  \lbd||rsp_a_n\  = M_J_CPU0_SA_RSP<0>
  \lbs||rsp_b_n\  = M_J_CPU0_SB_RSP<0>
  VSS38  = GND
  CB4_B  = M_J_CPU0_SB_CB<4>
  VSS39  = GND
  CB5_B  = M_J_CPU0_SB_CB<5>
  VSS40  = GND
  \dqs9_b_t||tdqs9_b_t||dbi4_b_n\  = M_J_CPU0_SB_DQS_DP<9>
  \dqs9_b_c||tdqs9_b_c\  = M_J_CPU0_SB_DQS_DN<9>
  VSS41  = GND
  CB0_B  = M_J_CPU0_SB_CB<0>
  VSS42  = GND
  CB1_B  = M_J_CPU0_SB_CB<1>
  VSS43  = GND
  DQ0_B  = M_J_CPU0_SB_DQ<0>
  VSS44  = GND
  DQ1_B  = M_J_CPU0_SB_DQ<1>
  VSS45  = GND
  DQS0_B_T  = M_J_CPU0_SB_DQS_DP<0>
  DQS0_B_C  = M_J_CPU0_SB_DQS_DN<0>
  VSS46  = GND
  DQ4_B  = M_J_CPU0_SB_DQ<4>
  VSS47  = GND
  DQ5_B  = M_J_CPU0_SB_DQ<5>
  VSS48  = GND
  DQ8_B  = M_J_CPU0_SB_DQ<8>
  VSS49  = GND
  DQ9_B  = M_J_CPU0_SB_DQ<9>
  VSS50  = GND
  DQS1_B_T  = M_J_CPU0_SB_DQS_DP<1>
  DQS1_B_C  = M_J_CPU0_SB_DQS_DN<1>
  VSS51  = GND
  DQ12_B  = M_J_CPU0_SB_DQ<12>
  VSS52  = GND
  DQ13_B  = M_J_CPU0_SB_DQ<13>
  VSS53  = GND
  DQ16_B  = M_J_CPU0_SB_DQ<16>
  VSS54  = GND
  DQ17_B  = M_J_CPU0_SB_DQ<17>
  VSS55  = GND
  DQS2_B_T  = M_J_CPU0_SB_DQS_DP<2>
  DQS2_B_C  = M_J_CPU0_SB_DQS_DN<2>
  VSS56  = GND
  DQ20_B  = M_J_CPU0_SB_DQ<20>
  VSS57  = GND
  DQ21_B  = M_J_CPU0_SB_DQ<21>
  VSS58  = GND
  DQ24_B  = M_J_CPU0_SB_DQ<24>
  VSS59  = GND
  DQ25_B  = M_J_CPU0_SB_DQ<25>
  VSS60  = GND
  DQS3_B_T  = M_J_CPU0_SB_DQS_DP<3>
  DQS3_B_C  = M_J_CPU0_SB_DQS_DN<3>
  VSS61  = GND
  DQ28_B  = M_J_CPU0_SB_DQ<28>
  VSS62  = GND
  DQ29_B  = M_J_CPU0_SB_DQ<29>
  VSS63  = GND
  RFU1  = NC
  VIN_BULK1  = P12V_MEM_CPU0
  VIN_BULK2  = P12V_MEM_CPU0
  \pwr_good||fail_n\  = PWRGD_CHJ_CPU0_DIMM
  HAS  = PD_CHJ_CPU0_DIMM_SAA
  RFU2  = NC
  RFU3  = NC
  VSS64  = GND
  DQ2_A  = M_J_CPU0_SA_DQ<2>
  VSS65  = GND
  DQ3_A  = M_J_CPU0_SA_DQ<3>
  VSS66  = GND
  \dqs5_a_c||tdqs5_a_c||dqs5_a_t||tdqs5_a_t\  = M_J_CPU0_SA_DQS_DN<5>
  \dqs5_a_t||tdqs5_a_t\  = M_J_CPU0_SA_DQS_DP<5>
  VSS67  = GND
  DQ6_A  = M_J_CPU0_SA_DQ<6>
  VSS68  = GND
  DQ7_A  = M_J_CPU0_SA_DQ<7>
  VSS69  = GND
  DQ10_A  = M_J_CPU0_SA_DQ<10>
  VSS70  = GND
  DQ11_A  = M_J_CPU0_SA_DQ<11>
  VSS71  = GND
  \dqs6_a_c||tdqs6_a_c||dqs6_a_t||tdqs6_a_t\  = M_J_CPU0_SA_DQS_DN<6>
  \dqs6_a_t||tdqs6_a_t\  = M_J_CPU0_SA_DQS_DP<6>
  VSS72  = GND
  DQ14_A  = M_J_CPU0_SA_DQ<14>
  VSS73  = GND
  DQ15_A  = M_J_CPU0_SA_DQ<15>
  VSS74  = GND
  DQ18_A  = M_J_CPU0_SA_DQ<18>
  VSS75  = GND
  DQ19_A  = M_J_CPU0_SA_DQ<19>
  VSS76  = GND
  \dqs7_a_c||tdqs7_a_c\  = M_J_CPU0_SA_DQS_DN<7>
  \dqs7_a_t||tdqs7_a_t\  = M_J_CPU0_SA_DQS_DP<7>
  VSS77  = GND
  DQ22_A  = M_J_CPU0_SA_DQ<22>
  VSS78  = GND
  DQ23_A  = M_J_CPU0_SA_DQ<23>
  VSS79  = GND
  DQ26_A  = M_J_CPU0_SA_DQ<26>
  VSS80  = GND
  DQ27_A  = M_J_CPU0_SA_DQ<27>
  VSS81  = GND
  \dqs8_a_c||tdqs8_a_c\  = M_J_CPU0_SA_DQS_DN<8>
  \dqs8_a_t||tdqs8_a_t\  = M_J_CPU0_SA_DQS_DP<8>
  VSS82  = GND
  DQ30_A  = M_J_CPU0_SA_DQ<30>
  VSS83  = GND
  DQ31_A  = M_J_CPU0_SA_DQ<31>
  VSS84  = GND
  CB2_A  = M_J_CPU0_SA_CB<2>
  VSS85  = GND
  CB3_A  = M_J_CPU0_SA_CB<3>
  VSS86  = GND
  \dqs9_a_c||tdqs9_a_c\  = M_J_CPU0_SA_DQS_DN<9>
  \dqs9_a_t||tdqs9_a_t\  = M_J_CPU0_SA_DQS_DP<9>
  VSS87  = GND
  CB6_A  = M_J_CPU0_SA_CB<6>
  VSS88  = GND
  CB7_A  = M_J_CPU0_SA_CB<7>
  VSS89  = GND
  RESET_N  = M_J_CPU0_RESET_N
  VSS90  = GND
  CS1_A_N  = M_J_CPU0_SA_CS_N<1>
  VSS91  = GND
  CA1_A  = M_J_CPU0_SA_CA<1>
  VSS92  = GND
  CA3_A  = M_J_CPU0_SA_CA<3>
  VSS93  = GND
  CA5_A  = M_J_CPU0_SA_CA<5>
  VSS94  = GND
  CK_T  = M_J_CPU0_CLK_DP<0>
  CK_C  = M_J_CPU0_CLK_DN<0>
  VSS95  = GND
  RFU4  = NC
  CA1_B  = M_J_CPU0_SB_CA<1>
  VSS96  = GND
  CA3_B  = M_J_CPU0_SB_CA<3>
  VSS97  = GND
  CA5_B  = M_J_CPU0_SB_CA<5>
  VSS98  = GND
  PAR_B  = M_J_CPU0_SB_PAR
  VSS99  = GND
  CS1_B_N  = M_J_CPU0_SB_CS_N<1>
  VSS100  = GND
  RFU5  = NC
  RFU6  = NC
  VSS101  = GND
  CB6_B  = M_J_CPU0_SB_CB<6>
  VSS102  = GND
  CB7_B  = M_J_CPU0_SB_CB<7>
  VSS103  = GND
  DQS4_B_C  = M_J_CPU0_SB_DQS_DN<4>
  DQS4_B_T  = M_J_CPU0_SB_DQS_DP<4>
  VSS104  = GND
  CB2_B  = M_J_CPU0_SB_CB<2>
  VSS105  = GND
  CB3_B  = M_J_CPU0_SB_CB<3>
  VSS106  = GND
  DQ2_B  = M_J_CPU0_SB_DQ<2>
  VSS107  = GND
  DQ3_B  = M_J_CPU0_SB_DQ<3>
  VSS108  = GND
  \dqs5_b_c||tdqs5_b_c\  = M_J_CPU0_SB_DQS_DN<5>
  \dqs5_b_t||tdqs5_b_t\  = M_J_CPU0_SB_DQS_DP<5>
  VSS109  = GND
  DQ6_B  = M_J_CPU0_SB_DQ<6>
  VSS110  = GND
  DQ7_B  = M_J_CPU0_SB_DQ<7>
  VSS111  = GND
  DQ10_B  = M_J_CPU0_SB_DQ<10>
  VSS112  = GND
  DQ11_B  = M_J_CPU0_SB_DQ<11>
  VSS113  = GND
  \dqs6_b_c||tdqs6_b_c\  = M_J_CPU0_SB_DQS_DN<6>
  \dqs6_b_t||tdqs6_b_t\  = M_J_CPU0_SB_DQS_DP<6>
  VSS114  = GND
  DQ14_B  = M_J_CPU0_SB_DQ<14>
  VSS115  = GND
  DQ15_B  = M_J_CPU0_SB_DQ<15>
  VSS116  = GND
  DQ18_B  = M_J_CPU0_SB_DQ<18>
  VSS117  = GND
  DQ19_B  = M_J_CPU0_SB_DQ<19>
  VSS118  = GND
  \dqs7_b_c||tdqs7_b_c\  = M_J_CPU0_SB_DQS_DN<7>
  \dqs7_b_t||tdqs7_b_t\  = M_J_CPU0_SB_DQS_DP<7>
  VSS119  = GND
  DQ22_B  = M_J_CPU0_SB_DQ<22>
  VSS120  = GND
  DQ23_B  = M_J_CPU0_SB_DQ<23>
  VSS121  = GND
  DQ26_B  = M_J_CPU0_SB_DQ<26>
  VSS122  = GND
  DQ27_B  = M_J_CPU0_SB_DQ<27>
  VSS123  = GND
  \dqs8_b_c||tdqs8_b_c\  = M_J_CPU0_SB_DQS_DN<8>
  \dqs8_b_t||tdqs8_b_t\  = M_J_CPU0_SB_DQS_DP<8>
  VSS124  = GND
  DQ30_B  = M_J_CPU0_SB_DQ<30>
  VSS125  = GND
  DQ31_B  = M_J_CPU0_SB_DQ<31>
  VSS126  = GND
  G1  = GND
  G2  = GND
  G3  = GND

(kicad_pcb
	(version 20260206)
	(generator "pcbnew")
	(generator_version "10.0")
	(general
		(thickness 1.6)
		(legacy_teardrops no)
	)
	(paper "A4")
	(title_block
		(title "04192023_DAF0TMB3IC0_F0TG_MB_C_brd_V02_OCP.brd")
		(comment 1 "Grand Teton / footprint 802 of 8354 (J68), pads 230-275 of 291")
	)
	(layers
		(0 "F.Cu" signal "TOP")
		(4 "In1.Cu" signal "GND")
		(6 "In2.Cu" signal "IN1")
		(8 "In3.Cu" signal "GND1")
		(10 "In4.Cu" signal "IN2")
		(12 "In5.Cu" signal "GND2")
		(14 "In6.Cu" signal "IN3")
		(16 "In7.Cu" signal "GND3")
		(18 "In8.Cu" signal "VCC")
		(20 "In9.Cu" signal "VCC1")
		(22 "In10.Cu" signal "GND4")
		(24 "In11.Cu" signal "IN4")
		(26 "In12.Cu" signal "GND5")
		(28 "In13.Cu" signal "IN5")
		(30 "In14.Cu" signal "GND6")
		(32 "In15.Cu" signal "IN6")
		(34 "In16.Cu" signal "GND7")
		(2 "B.Cu" signal "BOTTOM")
		(9 "F.Adhes" user "F.Adhesive")
		(11 "B.Adhes" user "B.Adhesive")
		(13 "F.Paste" user "Package Geometry/Pastemask Top")
		(15 "B.Paste" user "Package Geometry/Pastemask Bottom")
		(5 "F.SilkS" user "Ref Des/Silkscreen Top")
		(7 "B.SilkS" user "Ref Des/Silkscreen Bottom")
		(1 "F.Mask" user "Board Geometry/Soldermask Top")
		(3 "B.Mask" user "Board Geometry/Soldermask Bottom")
		(17 "Dwgs.User" user "User.Drawings")
		(19 "Cmts.User" user "User.Comments")
		(21 "Eco1.User" user "User.Eco1")
		(23 "Eco2.User" user "User.Eco2")
		(25 "Edge.Cuts" user "Board Geometry/Outline")
		(27 "Margin" user)
		(31 "F.CrtYd" user "Package Geometry/Place Bound Top")
		(29 "B.CrtYd" user "Package Geometry/Place Bound Bottom")
		(35 "F.Fab" user "Ref Des/Assembly Top")
		(33 "B.Fab" user "Ref Des/Assembly Bottom")
	)
	(footprint ""
		(layer "F.Cu")
		(at 437.05018 -255.560068 180)
		(property "Reference" "J68"
			(at 1.32334 -81.844388 0)
			(unlocked yes)
			(layer "F.SilkS")
			(effects
				(font
					(size 0.7874 0.5842)
					(thickness 0.1524)
				)
			)
		)
		(property "Value" ""
			(at 0 0 180)
			(layer "F.Fab")
			(effects
				(font
					(size 1.27 1.27)
				)
			)
		)
		(duplicate_pad_numbers_are_jumpers no)
		(pad "230" smd rect
			(at 2.050034 14.025118 90)
			(size 0.519938 1.4986)
			(layers "F.Cu" "F.Mask" "F.Paste")
			(net "GND")
		)
		(pad "231" smd rect
			(at 2.050034 14.875002 90)
			(size 0.519938 1.4986)
			(layers "F.Cu" "F.Mask" "F.Paste")
			(net "Net_2380")
		)
		(pad "232" smd rect
			(at 2.050034 15.724886 90)
			(size 0.519938 1.4986)
			(layers "F.Cu" "F.Mask" "F.Paste")
			(net "Net_2381")
		)
		(pad "233" smd rect
			(at 2.050034 16.575024 90)
			(size 0.519938 1.4986)
			(layers "F.Cu" "F.Mask" "F.Paste")
			(net "GND")
		)
		(pad "234" smd rect
			(at 2.050034 17.424908 90)
			(size 0.519938 1.4986)
			(layers "F.Cu" "F.Mask" "F.Paste")
			(net "M_J_CPU0_SB_CB<6>")
		)
		(pad "235" smd rect
			(at 2.050034 18.275046 90)
			(size 0.519938 1.4986)
			(layers "F.Cu" "F.Mask" "F.Paste")
			(net "GND")
		)
		(pad "236" smd rect
			(at 2.050034 19.12493 90)
			(size 0.519938 1.4986)
			(layers "F.Cu" "F.Mask" "F.Paste")
			(net "M_J_CPU0_SB_CB<7>")
		)
		(pad "237" smd rect
			(at 2.050034 19.975068 90)
			(size 0.519938 1.4986)
			(layers "F.Cu" "F.Mask" "F.Paste")
			(net "GND")
		)
		(pad "238" smd rect
			(at 2.050034 20.824952 90)
			(size 0.519938 1.4986)
			(layers "F.Cu" "F.Mask" "F.Paste")
			(net "M_J_CPU0_SB_DQS_DN<4>")
		)
		(pad "239" smd rect
			(at 2.050034 21.67509 90)
			(size 0.519938 1.4986)
			(layers "F.Cu" "F.Mask" "F.Paste")
			(net "M_J_CPU0_SB_DQS_DP<4>")
		)
		(pad "240" smd rect
			(at 2.050034 22.524974 90)
			(size 0.519938 1.4986)
			(layers "F.Cu" "F.Mask" "F.Paste")
			(net "GND")
		)
		(pad "241" smd rect
			(at 2.050034 23.375112 90)
			(size 0.519938 1.4986)
			(layers "F.Cu" "F.Mask" "F.Paste")
			(net "M_J_CPU0_SB_CB<2>")
		)
		(pad "242" smd rect
			(at 2.050034 24.224996 90)
			(size 0.519938 1.4986)
			(layers "F.Cu" "F.Mask" "F.Paste")
			(net "GND")
		)
		(pad "243" smd rect
			(at 2.050034 25.07488 90)
			(size 0.519938 1.4986)
			(layers "F.Cu" "F.Mask" "F.Paste")
			(net "M_J_CPU0_SB_CB<3>")
		)
		(pad "244" smd rect
			(at 2.050034 25.925018 90)
			(size 0.519938 1.4986)
			(layers "F.Cu" "F.Mask" "F.Paste")
			(net "GND")
		)
		(pad "245" smd rect
			(at 2.050034 26.774902 90)
			(size 0.519938 1.4986)
			(layers "F.Cu" "F.Mask" "F.Paste")
			(net "M_J_CPU0_SB_DQ<2>")
		)
		(pad "246" smd rect
			(at 2.050034 27.62504 90)
			(size 0.519938 1.4986)
			(layers "F.Cu" "F.Mask" "F.Paste")
			(net "GND")
		)
		(pad "247" smd rect
			(at 2.050034 28.474924 90)
			(size 0.519938 1.4986)
			(layers "F.Cu" "F.Mask" "F.Paste")
			(net "M_J_CPU0_SB_DQ<3>")
		)
		(pad "248" smd rect
			(at 2.050034 29.325062 90)
			(size 0.519938 1.4986)
			(layers "F.Cu" "F.Mask" "F.Paste")
			(net "GND")
		)
		(pad "249" smd rect
			(at 2.050034 30.174946 90)
			(size 0.519938 1.4986)
			(layers "F.Cu" "F.Mask" "F.Paste")
			(net "M_J_CPU0_SB_DQS_DN<5>")
		)
		(pad "250" smd rect
			(at 2.050034 31.025084 90)
			(size 0.519938 1.4986)
			(layers "F.Cu" "F.Mask" "F.Paste")
			(net "M_J_CPU0_SB_DQS_DP<5>")
		)
		(pad "251" smd rect
			(at 2.050034 31.874968 90)
			(size 0.519938 1.4986)
			(layers "F.Cu" "F.Mask" "F.Paste")
			(net "GND")
		)
		(pad "252" smd rect
			(at 2.050034 32.725106 90)
			(size 0.519938 1.4986)
			(layers "F.Cu" "F.Mask" "F.Paste")
			(net "M_J_CPU0_SB_DQ<6>")
		)
		(pad "253" smd rect
			(at 2.050034 33.57499 90)
			(size 0.519938 1.4986)
			(layers "F.Cu" "F.Mask" "F.Paste")
			(net "GND")
		)
		(pad "254" smd rect
			(at 2.050034 34.425128 90)
			(size 0.519938 1.4986)
			(layers "F.Cu" "F.Mask" "F.Paste")
			(net "M_J_CPU0_SB_DQ<7>")
		)
		(pad "255" smd rect
			(at 2.050034 35.275012 90)
			(size 0.519938 1.4986)
			(layers "F.Cu" "F.Mask" "F.Paste")
			(net "GND")
		)
		(pad "256" smd rect
			(at 2.050034 36.124896 90)
			(size 0.519938 1.4986)
			(layers "F.Cu" "F.Mask" "F.Paste")
			(net "M_J_CPU0_SB_DQ<10>")
		)
		(pad "257" smd rect
			(at 2.050034 36.975034 90)
			(size 0.519938 1.4986)
			(layers "F.Cu" "F.Mask" "F.Paste")
			(net "GND")
		)
		(pad "258" smd rect
			(at 2.050034 37.824918 90)
			(size 0.519938 1.4986)
			(layers "F.Cu" "F.Mask" "F.Paste")
			(net "M_J_CPU0_SB_DQ<11>")
		)
		(pad "259" smd rect
			(at 2.050034 38.675056 90)
			(size 0.519938 1.4986)
			(layers "F.Cu" "F.Mask" "F.Paste")
			(net "GND")
		)
		(pad "260" smd rect
			(at 2.050034 39.52494 90)
			(size 0.519938 1.4986)
			(layers "F.Cu" "F.Mask" "F.Paste")
			(net "M_J_CPU0_SB_DQS_DN<6>")
		)
		(pad "261" smd rect
			(at 2.050034 40.375078 90)
			(size 0.519938 1.4986)
			(layers "F.Cu" "F.Mask" "F.Paste")
			(net "M_J_CPU0_SB_DQS_DP<6>")
		)
		(pad "262" smd rect
			(at 2.050034 41.224962 90)
			(size 0.519938 1.4986)
			(layers "F.Cu" "F.Mask" "F.Paste")
			(net "GND")
		)
		(pad "263" smd rect
			(at 2.050034 42.0751 90)
			(size 0.519938 1.4986)
			(layers "F.Cu" "F.Mask" "F.Paste")
			(net "M_J_CPU0_SB_DQ<14>")
		)
		(pad "264" smd rect
			(at 2.050034 42.924984 90)
			(size 0.519938 1.4986)
			(layers "F.Cu" "F.Mask" "F.Paste")
			(net "GND")
		)
		(pad "265" smd rect
			(at 2.050034 43.775122 90)
			(size 0.519938 1.4986)
			(layers "F.Cu" "F.Mask" "F.Paste")
			(net "M_J_CPU0_SB_DQ<15>")
		)
		(pad "266" smd rect
			(at 2.050034 44.625006 90)
			(size 0.519938 1.4986)
			(layers "F.Cu" "F.Mask" "F.Paste")
			(net "GND")
		)
		(pad "267" smd rect
			(at 2.050034 45.47489 90)
			(size 0.519938 1.4986)
			(layers "F.Cu" "F.Mask" "F.Paste")
			(net "M_J_CPU0_SB_DQ<18>")
		)
		(pad "268" smd rect
			(at 2.050034 46.325028 90)
			(size 0.519938 1.4986)
			(layers "F.Cu" "F.Mask" "F.Paste")
			(net "GND")
		)
		(pad "269" smd rect
			(at 2.050034 47.174912 90)
			(size 0.519938 1.4986)
			(layers "F.Cu" "F.Mask" "F.Paste")
			(net "M_J_CPU0_SB_DQ<19>")
		)
		(pad "270" smd rect
			(at 2.050034 48.02505 90)
			(size 0.519938 1.4986)
			(layers "F.Cu" "F.Mask" "F.Paste")
			(net "GND")
		)
		(pad "271" smd rect
			(at 2.050034 48.874934 90)
			(size 0.519938 1.4986)
			(layers "F.Cu" "F.Mask" "F.Paste")
			(net "M_J_CPU0_SB_DQS_DN<7>")
		)
		(pad "272" smd rect
			(at 2.050034 49.725072 90)
			(size 0.519938 1.4986)
			(layers "F.Cu" "F.Mask" "F.Paste")
			(net "M_J_CPU0_SB_DQS_DP<7>")
		)
		(pad "273" smd rect
			(at 2.050034 50.574956 90)
			(size 0.519938 1.4986)
			(layers "F.Cu" "F.Mask" "F.Paste")
			(net "GND")
		)
		(pad "274" smd rect
			(at 2.050034 51.425094 90)
			(size 0.519938 1.4986)
			(layers "F.Cu" "F.Mask" "F.Paste")
			(net "M_J_CPU0_SB_DQ<22>")
		)
		(pad "275" smd rect
			(at 2.050034 52.274978 90)
			(size 0.519938 1.4986)
			(layers "F.Cu" "F.Mask" "F.Paste")
			(net "GND")
		)
	)
)
